# T6G (Grand Teton) — schematic netlist excerpt (pin names and nets, part order shuffled) for the footprints in the layout excerpt that follows; sources: Cadence DE-HDL packaged netlist, KiCad conversion of 04192023_DAF0TMB3IC0_F0TG_MB_C_brd_V02_OCP.brd

R751  Q_RES  10K 5% CHIP  pkg 0402LF  page 76 : A = GND ; B = CLK_CPU0_RTCCLK
C6101  Q_CAP  0.1UF 25V 10% X7R  pkg 0402  page 179 : A = P3V3_AUX_CPU0_USB2_AVDD33 ; B = GND

(kicad_pcb
	(version 20260206)
	(generator "pcbnew")
	(generator_version "10.0")
	(general
		(thickness 1.6)
		(legacy_teardrops no)
	)
	(paper "A4")
	(title_block
		(title "04192023_DAF0TMB3IC0_F0TG_MB_C_brd_V02_OCP.brd")
		(comment 1 "Grand Teton / footprints 7505-7506 of 8354")
	)
	(layers
		(0 "F.Cu" signal "TOP")
		(4 "In1.Cu" signal "GND")
		(6 "In2.Cu" signal "IN1")
		(8 "In3.Cu" signal "GND1")
		(10 "In4.Cu" signal "IN2")
		(12 "In5.Cu" signal "GND2")
		(14 "In6.Cu" signal "IN3")
		(16 "In7.Cu" signal "GND3")
		(18 "In8.Cu" signal "VCC")
		(20 "In9.Cu" signal "VCC1")
		(22 "In10.Cu" signal "GND4")
		(24 "In11.Cu" signal "IN4")
		(26 "In12.Cu" signal "GND5")
		(28 "In13.Cu" signal "IN5")
		(30 "In14.Cu" signal "GND6")
		(32 "In15.Cu" signal "IN6")
		(34 "In16.Cu" signal "GND7")
		(2 "B.Cu" signal "BOTTOM")
		(9 "F.Adhes" user "F.Adhesive")
		(11 "B.Adhes" user "B.Adhesive")
		(13 "F.Paste" user "Package Geometry/Pastemask Top")
		(15 "B.Paste" user "Package Geometry/Pastemask Bottom")
		(5 "F.SilkS" user "Ref Des/Silkscreen Top")
		(7 "B.SilkS" user "Ref Des/Silkscreen Bottom")
		(1 "F.Mask" user "Board Geometry/Soldermask Top")
		(3 "B.Mask" user "Board Geometry/Soldermask Bottom")
		(17 "Dwgs.User" user "User.Drawings")
		(19 "Cmts.User" user "User.Comments")
		(21 "Eco1.User" user "User.Eco1")
		(23 "Eco2.User" user "User.Eco2")
		(25 "Edge.Cuts" user "Board Geometry/Outline")
		(27 "Margin" user)
		(31 "F.CrtYd" user "Package Geometry/Place Bound Top")
		(29 "B.CrtYd" user "Package Geometry/Place Bound Bottom")
		(35 "F.Fab" user "Ref Des/Assembly Top")
		(33 "B.Fab" user "Ref Des/Assembly Bottom")
	)
	(footprint ""
		(layer "B.Cu")
		(at 391.104628 -314.180474 90)
		(property "Reference" "R751"
			(at 0 0 90)
			(layer "B.SilkS")
			(hide yes)
			(effects
				(font
					(size 1.27 1.27)
				)
				(justify mirror)
			)
		)
		(property "Value" ""
			(at 0 0 90)
			(layer "B.Fab")
			(effects
				(font
					(size 1.27 1.27)
				)
				(justify mirror)
			)
		)
		(duplicate_pad_numbers_are_jumpers no)
		(fp_line
			(start 0.7874 -0.4064)
			(end -0.7874 -0.4064)
			(stroke
				(width 0.1524)
				(type default)
			)
			(layer "B.SilkS")
		)
		(fp_line
			(start -0.7874 -0.4064)
			(end -0.7874 0.4064)
			(stroke
				(width 0.1524)
				(type default)
			)
			(layer "B.SilkS")
		)
		(fp_line
			(start 0.7874 0.4064)
			(end 0.7874 -0.4064)
			(stroke
				(width 0.1524)
				(type default)
			)
			(layer "B.SilkS")
		)
		(fp_line
			(start -0.7874 0.4064)
			(end 0.7874 0.4064)
			(stroke
				(width 0.1524)
				(type default)
			)
			(layer "B.SilkS")
		)
		(fp_line
			(start 0.67945 -0.305054)
			(end 0.12065 -0.305054)
			(stroke
				(width 0.1)
				(type default)
			)
			(layer "B.Fab")
		)
		(fp_line
			(start 0.12065 -0.305054)
			(end 0.12065 -0.2794)
			(stroke
				(width 0.1)
				(type default)
			)
			(layer "B.Fab")
		)
		(fp_line
			(start -0.12065 -0.3048)
			(end -0.67945 -0.3048)
			(stroke
				(width 0.1)
				(type default)
			)
			(layer "B.Fab")
		)
		(fp_line
			(start -0.67945 -0.3048)
			(end -0.67945 0.3048)
			(stroke
				(width 0.1)
				(type default)
			)
			(layer "B.Fab")
		)
		(fp_line
			(start 0.12065 -0.2794)
			(end -0.12065 -0.2794)
			(stroke
				(width 0.1)
				(type default)
			)
			(layer "B.Fab")
		)
		(fp_line
			(start -0.12065 -0.2794)
			(end -0.12065 -0.3048)
			(stroke
				(width 0.1)
				(type default)
			)
			(layer "B.Fab")
		)
		(fp_line
			(start 0.12065 0.2794)
			(end 0.12065 0.3048)
			(stroke
				(width 0.1)
				(type default)
			)
			(layer "B.Fab")
		)
		(fp_line
			(start -0.120396 0.2794)
			(end 0.12065 0.2794)
			(stroke
				(width 0.1)
				(type default)
			)
			(layer "B.Fab")
		)
		(fp_line
			(start 0.67945 0.3048)
			(end 0.67945 -0.305054)
			(stroke
				(width 0.1)
				(type default)
			)
			(layer "B.Fab")
		)
		(fp_line
			(start 0.12065 0.3048)
			(end 0.67945 0.3048)
			(stroke
				(width 0.1)
				(type default)
			)
			(layer "B.Fab")
		)
		(fp_line
			(start -0.120396 0.3048)
			(end -0.120396 0.2794)
			(stroke
				(width 0.1)
				(type default)
			)
			(layer "B.Fab")
		)
		(fp_line
			(start -0.67945 0.3048)
			(end -0.120396 0.3048)
			(stroke
				(width 0.1)
				(type default)
			)
			(layer "B.Fab")
		)
		(pad "1" smd circle
			(at 0.40005 0 270)
			(size 0 0)
			(layers "B.Cu" "B.Mask" "B.Paste")
			(net "GND")
		)
		(pad "2" smd circle
			(at -0.40005 0 270)
			(size 0 0)
			(layers "B.Cu" "B.Mask" "B.Paste")
			(net "CLK_CPU0_RTCCLK")
		)
	)
	(footprint ""
		(layer "B.Cu")
		(at 106.901996 -26.952448 90)
		(property "Reference" "C6101"
			(at 0 0 90)
			(layer "B.SilkS")
			(hide yes)
			(effects
				(font
					(size 1.27 1.27)
				)
				(justify mirror)
			)
		)
		(property "Value" ""
			(at 0 0 90)
			(layer "B.Fab")
			(effects
				(font
					(size 1.27 1.27)
				)
				(justify mirror)
			)
		)
		(duplicate_pad_numbers_are_jumpers no)
		(fp_line
			(start 0.7874 -0.4064)
			(end -0.7874 -0.4064)
			(stroke
				(width 0.1524)
				(type default)
			)
			(layer "B.SilkS")
		)
		(fp_line
			(start -0.7874 -0.4064)
			(end -0.7874 0.4064)
			(stroke
				(width 0.1524)
				(type default)
			)
			(layer "B.SilkS")
		)
		(fp_line
			(start 0.7874 0.4064)
			(end 0.7874 -0.4064)
			(stroke
				(width 0.1524)
				(type default)
			)
			(layer "B.SilkS")
		)
		(fp_line
			(start -0.7874 0.4064)
			(end 0.7874 0.4064)
			(stroke
				(width 0.1524)
				(type default)
			)
			(layer "B.SilkS")
		)
		(fp_line
			(start 0.67945 -0.305054)
			(end 0.12065 -0.305054)
			(stroke
				(width 0.1)
				(type default)
			)
			(layer "B.Fab")
		)
		(fp_line
			(start 0.12065 -0.305054)
			(end 0.12065 -0.2794)
			(stroke
				(width 0.1)
				(type default)
			)
			(layer "B.Fab")
		)
		(fp_line
			(start -0.12065 -0.3048)
			(end -0.67945 -0.3048)
			(stroke
				(width 0.1)
				(type default)
			)
			(layer "B.Fab")
		)
		(fp_line
			(start -0.67945 -0.3048)
			(end -0.67945 0.3048)
			(stroke
				(width 0.1)
				(type default)
			)
			(layer "B.Fab")
		)
		(fp_line
			(start 0.12065 -0.2794)
			(end -0.12065 -0.2794)
			(stroke
				(width 0.1)
				(type default)
			)
			(layer "B.Fab")
		)
		(fp_line
			(start -0.12065 -0.2794)
			(end -0.12065 -0.3048)
			(stroke
				(width 0.1)
				(type default)
			)
			(layer "B.Fab")
		)
		(fp_line
			(start 0.12065 0.2794)
			(end 0.12065 0.3048)
			(stroke
				(width 0.1)
				(type default)
			)
			(layer "B.Fab")
		)
		(fp_line
			(start -0.120396 0.2794)
			(end 0.12065 0.2794)
			(stroke
				(width 0.1)
				(type default)
			)
			(layer "B.Fab")
		)
		(fp_line
			(start 0.67945 0.3048)
			(end 0.67945 -0.305054)
			(stroke
				(width 0.1)
				(type default)
			)
			(layer "B.Fab")
		)
		(fp_line
			(start 0.12065 0.3048)
			(end 0.67945 0.3048)
			(stroke
				(width 0.1)
				(type default)
			)
			(layer "B.Fab")
		)
		(fp_line
			(start -0.120396 0.3048)
			(end -0.120396 0.2794)
			(stroke
				(width 0.1)
				(type default)
			)
			(layer "B.Fab")
		)
		(fp_line
			(start -0.67945 0.3048)
			(end -0.120396 0.3048)
			(stroke
				(width 0.1)
				(type default)
			)
			(layer "B.Fab")
		)
		(pad "1" smd circle
			(at 0.40005 0 270)
			(size 0 0)
			(layers "B.Cu" "B.Mask" "B.Paste")
			(net "P3V3_AUX_CPU0_USB2_AVDD33")
		)
		(pad "2" smd circle
			(at -0.40005 0 270)
			(size 0 0)
			(layers "B.Cu" "B.Mask" "B.Paste")
			(net "GND")
		)
	)
)
